(kicad_pcb
	(version 20260206)
	(generator "pcbnew")
	(generator_version "10.0")
	(general
		(thickness 1.6)
		(legacy_teardrops no)
	)
	(paper "A4")
	(title_block
		(title "Bryce Canyon_SCC_16316-1_OCP.brd")
		(comment 1 "Bryce Canyon / footprints 1042-1049 of 1561")
	)
	(layers
		(0 "F.Cu" signal "TOP")
		(4 "In1.Cu" signal "L2GND")
		(6 "In2.Cu" signal "L3")
		(8 "In3.Cu" signal "L4VCC")
		(10 "In4.Cu" signal "L5VCC")
		(12 "In5.Cu" signal "L6")
		(14 "In6.Cu" signal "L7GND")
		(2 "B.Cu" signal "BOTTOM")
		(9 "F.Adhes" user "F.Adhesive")
		(11 "B.Adhes" user "B.Adhesive")
		(13 "F.Paste" user "Package Geometry/Pastemask Top")
		(15 "B.Paste" user "Package Geometry/Pastemask Bottom")
		(5 "F.SilkS" user "Ref Des/Silkscreen Top")
		(7 "B.SilkS" user "Ref Des/Silkscreen Bottom")
		(1 "F.Mask" user "Board Geometry/Soldermask Top")
		(3 "B.Mask" user "Board Geometry/Soldermask Bottom")
		(17 "Dwgs.User" user "User.Drawings")
		(19 "Cmts.User" user "User.Comments")
		(21 "Eco1.User" user "User.Eco1")
		(23 "Eco2.User" user "User.Eco2")
		(25 "Edge.Cuts" user "Board Geometry/Outline")
		(27 "Margin" user)
		(31 "F.CrtYd" user "Package Geometry/Place Bound Top")
		(29 "B.CrtYd" user "Package Geometry/Place Bound Bottom")
		(35 "F.Fab" user "Ref Des/Assembly Top")
		(33 "B.Fab" user "Ref Des/Assembly Bottom")
	)
	(footprint ""
		(layer "B.Cu")
		(at 166.64432 -20.572984)
		(property "Reference" "C313"
			(at 0 0 0)
			(layer "B.SilkS")
			(hide yes)
			(effects
				(font
					(size 1.27 1.27)
				)
				(justify mirror)
			)
		)
		(property "Value" "SCD22U10V1KX-GP"
			(at 2.8321 -1.7399 0)
			(unlocked yes)
			(layer "B.Fab")
			(hide yes)
			(effects
				(font
					(size 1.016 1.016)
					(thickness 0.1524)
				)
				(justify mirror)
			)
		)
		(property "Device Type" "C0201H13"
			(at 2.8321 -3.2639 0)
			(unlocked yes)
			(layer "B.Fab")
			(hide yes)
			(effects
				(font
					(size 1.016 1.016)
					(thickness 0.1524)
				)
				(justify mirror)
			)
		)
		(duplicate_pad_numbers_are_jumpers no)
		(fp_rect
			(start 0.2794 0.6477)
			(end -0.2794 -0.6477)
			(stroke
				(width 0)
				(type default)
			)
			(fill no)
			(layer "B.CrtYd")
		)
		(fp_rect
			(start 0.2794 0.6477)
			(end -0.2794 -0.6477)
			(stroke
				(width 0)
				(type default)
			)
			(fill no)
			(layer "B.Fab")
		)
		(pad "1" smd custom
			(at 0 -0.2794 180)
			(size 0.0762 0.0762)
			(layers "B.Cu" "B.Mask" "B.Paste")
			(net "PCIE_SCC_TO_COMP_C_1_DP")
			(options
				(clearance outline)
				(anchor circle)
			)
			(primitives
				(gr_poly
					(pts
						(arc
							(start 0.1524 0.127)
							(mid 0.137521 0.162921)
							(end 0.1016 0.1778)
						)
						(arc
							(start -0.1016 0.1778)
							(mid -0.137521 0.162921)
							(end -0.1524 0.127)
						)
						(arc
							(start -0.1524 -0.127)
							(mid -0.137521 -0.162921)
							(end -0.1016 -0.1778)
						)
						(arc
							(start 0.1016 -0.1778)
							(mid 0.137521 -0.162921)
							(end 0.1524 -0.127)
						)
					)
					(width 0)
					(fill yes)
				)
			)
		)
		(pad "2" smd custom
			(at 0 0.2794 180)
			(size 0.0762 0.0762)
			(layers "B.Cu" "B.Mask" "B.Paste")
			(net "PCIE_SCC_TO_COMP_1_DP")
			(options
				(clearance outline)
				(anchor circle)
			)
			(primitives
				(gr_poly
					(pts
						(arc
							(start 0.1524 0.127)
							(mid 0.137521 0.162921)
							(end 0.1016 0.1778)
						)
						(arc
							(start -0.1016 0.1778)
							(mid -0.137521 0.162921)
							(end -0.1524 0.127)
						)
						(arc
							(start -0.1524 -0.127)
							(mid -0.137521 -0.162921)
							(end -0.1016 -0.1778)
						)
						(arc
							(start 0.1016 -0.1778)
							(mid 0.137521 -0.162921)
							(end 0.1524 -0.127)
						)
					)
					(width 0)
					(fill yes)
				)
			)
		)
	)
	(footprint ""
		(layer "B.Cu")
		(at 166.624 -52.07)
		(property "Reference" "R268"
			(at 0 0 0)
			(layer "B.SilkS")
			(hide yes)
			(effects
				(font
					(size 1.27 1.27)
				)
				(justify mirror)
			)
		)
		(property "Value" "4K7R2F-GP"
			(at -0.064008 -3.993896 0)
			(unlocked yes)
			(layer "B.Fab")
			(hide yes)
			(effects
				(font
					(size 1.016 1.016)
					(thickness 0.1524)
				)
				(justify mirror)
			)
		)
		(property "Device Type" "R402H16"
			(at -0.064008 -5.517896 0)
			(unlocked yes)
			(layer "B.Fab")
			(hide yes)
			(effects
				(font
					(size 1.016 1.016)
					(thickness 0.1524)
				)
				(justify mirror)
			)
		)
		(duplicate_pad_numbers_are_jumpers no)
		(fp_line
			(start -0.508 -0.9398)
			(end 0.508 -0.9398)
			(stroke
				(width 0.1524)
				(type default)
			)
			(layer "B.SilkS")
		)
		(fp_line
			(start 0.508 -0.9398)
			(end 0.508 0.9398)
			(stroke
				(width 0.1524)
				(type default)
			)
			(layer "B.SilkS")
		)
		(fp_rect
			(start 0.508 0.9398)
			(end -0.508 -0.9398)
			(stroke
				(width 0)
				(type default)
			)
			(fill no)
			(layer "B.CrtYd")
		)
		(fp_rect
			(start 0.508 0.9398)
			(end -0.508 -0.9398)
			(stroke
				(width 0)
				(type default)
			)
			(fill no)
			(layer "B.Fab")
		)
		(pad "1" smd custom
			(at 0 -0.4445 180)
			(size 0.1397 0.1397)
			(layers "B.Cu" "B.Mask" "B.Paste")
			(net "P1V8_C")
			(options
				(clearance outline)
				(anchor circle)
			)
			(primitives
				(gr_poly
					(pts
						(arc
							(start -0.1778 0.2794)
							(mid -0.249642 0.249642)
							(end -0.2794 0.1778)
						)
						(arc
							(start -0.2794 -0.1778)
							(mid -0.249642 -0.249642)
							(end -0.1778 -0.2794)
						)
						(arc
							(start 0.1778 -0.2794)
							(mid 0.249642 -0.249642)
							(end 0.2794 -0.1778)
						)
						(arc
							(start 0.2794 0.1778)
							(mid 0.249642 0.249642)
							(end 0.1778 0.2794)
						)
					)
					(width 0)
					(fill yes)
				)
			)
		)
		(pad "2" smd custom
			(at 0 0.4445 180)
			(size 0.1397 0.1397)
			(layers "B.Cu" "B.Mask" "B.Paste")
			(net "ICE_SEL")
			(options
				(clearance outline)
				(anchor circle)
			)
			(primitives
				(gr_poly
					(pts
						(arc
							(start -0.1778 0.2794)
							(mid -0.249642 0.249642)
							(end -0.2794 0.1778)
						)
						(arc
							(start -0.2794 -0.1778)
							(mid -0.249642 -0.249642)
							(end -0.1778 -0.2794)
						)
						(arc
							(start 0.1778 -0.2794)
							(mid 0.249642 -0.249642)
							(end 0.2794 -0.1778)
						)
						(arc
							(start 0.2794 0.1778)
							(mid 0.249642 0.249642)
							(end 0.1778 0.2794)
						)
					)
					(width 0)
					(fill yes)
				)
			)
		)
	)
	(footprint ""
		(layer "B.Cu")
		(at 168.028874 -96.109282 180)
		(property "Reference" "R483"
			(at 0 0 0)
			(layer "B.SilkS")
			(hide yes)
			(effects
				(font
					(size 1.27 1.27)
				)
				(justify mirror)
			)
		)
		(property "Value" "10KR2F-2-GP"
			(at -0.064008 -3.993896 180)
			(unlocked yes)
			(layer "B.Fab")
			(hide yes)
			(effects
				(font
					(size 1.016 1.016)
					(thickness 0.1524)
				)
				(justify mirror)
			)
		)
		(property "Device Type" "R402H16"
			(at -0.064008 -5.517896 180)
			(unlocked yes)
			(layer "B.Fab")
			(hide yes)
			(effects
				(font
					(size 1.016 1.016)
					(thickness 0.1524)
				)
				(justify mirror)
			)
		)
		(duplicate_pad_numbers_are_jumpers no)
		(fp_line
			(start 0.508 -0.9398)
			(end 0.508 0.9398)
			(stroke
				(width 0.1524)
				(type default)
			)
			(layer "B.SilkS")
		)
		(fp_line
			(start -0.508 -0.9398)
			(end 0.508 -0.9398)
			(stroke
				(width 0.1524)
				(type default)
			)
			(layer "B.SilkS")
		)
		(fp_rect
			(start 0.508 0.9398)
			(end -0.508 -0.9398)
			(stroke
				(width 0)
				(type default)
			)
			(fill no)
			(layer "B.CrtYd")
		)
		(fp_rect
			(start 0.508 0.9398)
			(end -0.508 -0.9398)
			(stroke
				(width 0)
				(type default)
			)
			(fill no)
			(layer "B.Fab")
		)
		(pad "1" smd custom
			(at 0 -0.4445)
			(size 0.1397 0.1397)
			(layers "B.Cu" "B.Mask" "B.Paste")
			(net "AGND_P0V975")
			(options
				(clearance outline)
				(anchor circle)
			)
			(primitives
				(gr_poly
					(pts
						(arc
							(start -0.1778 0.2794)
							(mid -0.249642 0.249642)
							(end -0.2794 0.1778)
						)
						(arc
							(start -0.2794 -0.1778)
							(mid -0.249642 -0.249642)
							(end -0.1778 -0.2794)
						)
						(arc
							(start 0.1778 -0.2794)
							(mid 0.249642 -0.249642)
							(end 0.2794 -0.1778)
						)
						(arc
							(start 0.2794 0.1778)
							(mid 0.249642 0.249642)
							(end 0.1778 0.2794)
						)
					)
					(width 0)
					(fill yes)
				)
			)
		)
		(pad "2" smd custom
			(at 0 0.4445)
			(size 0.1397 0.1397)
			(layers "B.Cu" "B.Mask" "B.Paste")
			(net "VT235_IMAX")
			(options
				(clearance outline)
				(anchor circle)
			)
			(primitives
				(gr_poly
					(pts
						(arc
							(start -0.1778 0.2794)
							(mid -0.249642 0.249642)
							(end -0.2794 0.1778)
						)
						(arc
							(start -0.2794 -0.1778)
							(mid -0.249642 -0.249642)
							(end -0.1778 -0.2794)
						)
						(arc
							(start 0.1778 -0.2794)
							(mid 0.249642 -0.249642)
							(end 0.2794 -0.1778)
						)
						(arc
							(start 0.2794 0.1778)
							(mid 0.249642 0.249642)
							(end 0.1778 0.2794)
						)
					)
					(width 0)
					(fill yes)
				)
			)
		)
	)
	(footprint ""
		(layer "B.Cu")
		(at 118.7704 -61.488066)
		(property "Reference" "C226"
			(at 0 0 0)
			(layer "B.SilkS")
			(hide yes)
			(effects
				(font
					(size 1.27 1.27)
				)
				(justify mirror)
			)
		)
		(property "Value" "SCD1U16V2KX-3GP"
			(at -1.1811 -2.7051 0)
			(unlocked yes)
			(layer "B.Fab")
			(hide yes)
			(effects
				(font
					(size 1.016 1.016)
					(thickness 0.1524)
				)
				(justify mirror)
			)
		)
		(property "Device Type" "C402H22"
			(at -1.1811 -4.2291 0)
			(unlocked yes)
			(layer "B.Fab")
			(hide yes)
			(effects
				(font
					(size 1.016 1.016)
					(thickness 0.1524)
				)
				(justify mirror)
			)
		)
		(duplicate_pad_numbers_are_jumpers no)
		(fp_rect
			(start 0.4318 0.9525)
			(end -0.4318 -0.9525)
			(stroke
				(width 0)
				(type default)
			)
			(fill no)
			(layer "B.CrtYd")
		)
		(fp_rect
			(start 0.4318 0.9525)
			(end -0.4318 -0.9525)
			(stroke
				(width 0)
				(type default)
			)
			(fill no)
			(layer "B.Fab")
		)
		(pad "1" smd custom
			(at 0 -0.4445 180)
			(size 0.1524 0.1524)
			(layers "B.Cu" "B.Mask" "B.Paste")
			(net "GB_VDDH")
			(options
				(clearance outline)
				(anchor circle)
			)
			(primitives
				(gr_poly
					(pts
						(arc
							(start 0.3048 0.2032)
							(mid 0.275042 0.275042)
							(end 0.2032 0.3048)
						)
						(arc
							(start -0.2032 0.3048)
							(mid -0.275042 0.275042)
							(end -0.3048 0.2032)
						)
						(arc
							(start -0.3048 -0.2032)
							(mid -0.275042 -0.275042)
							(end -0.2032 -0.3048)
						)
						(arc
							(start 0.2032 -0.3048)
							(mid 0.275042 -0.275042)
							(end 0.3048 -0.2032)
						)
					)
					(width 0)
					(fill yes)
				)
			)
		)
		(pad "2" smd custom
			(at 0 0.4445 180)
			(size 0.1524 0.1524)
			(layers "B.Cu" "B.Mask" "B.Paste")
			(net "GND")
			(options
				(clearance outline)
				(anchor circle)
			)
			(primitives
				(gr_poly
					(pts
						(arc
							(start 0.3048 0.2032)
							(mid 0.275042 0.275042)
							(end 0.2032 0.3048)
						)
						(arc
							(start -0.2032 0.3048)
							(mid -0.275042 0.275042)
							(end -0.3048 0.2032)
						)
						(arc
							(start -0.3048 -0.2032)
							(mid -0.275042 -0.275042)
							(end -0.2032 -0.3048)
						)
						(arc
							(start 0.2032 -0.3048)
							(mid 0.275042 -0.275042)
							(end 0.3048 -0.2032)
						)
					)
					(width 0)
					(fill yes)
				)
			)
		)
	)
	(footprint ""
		(layer "B.Cu")
		(at 115.4938 -44.2214 180)
		(property "Reference" "C63"
			(at 0 0 0)
			(layer "B.SilkS")
			(hide yes)
			(effects
				(font
					(size 1.27 1.27)
				)
				(justify mirror)
			)
		)
		(property "Value" "SCD01U16V1KX-GP"
			(at 2.8321 -1.7399 180)
			(unlocked yes)
			(layer "B.Fab")
			(hide yes)
			(effects
				(font
					(size 1.016 1.016)
					(thickness 0.1524)
				)
				(justify mirror)
			)
		)
		(property "Device Type" "C0201H13"
			(at 2.8321 -3.2639 180)
			(unlocked yes)
			(layer "B.Fab")
			(hide yes)
			(effects
				(font
					(size 1.016 1.016)
					(thickness 0.1524)
				)
				(justify mirror)
			)
		)
		(duplicate_pad_numbers_are_jumpers no)
		(fp_rect
			(start 0.2794 0.6477)
			(end -0.2794 -0.6477)
			(stroke
				(width 0)
				(type default)
			)
			(fill no)
			(layer "B.CrtYd")
		)
		(fp_rect
			(start 0.2794 0.6477)
			(end -0.2794 -0.6477)
			(stroke
				(width 0)
				(type default)
			)
			(fill no)
			(layer "B.Fab")
		)
		(pad "1" smd custom
			(at 0 -0.2794)
			(size 0.0762 0.0762)
			(layers "B.Cu" "B.Mask" "B.Paste")
			(net "PHY_DPB_TO_SCC_32_DP")
			(options
				(clearance outline)
				(anchor circle)
			)
			(primitives
				(gr_poly
					(pts
						(arc
							(start 0.1524 0.127)
							(mid 0.137521 0.162921)
							(end 0.1016 0.1778)
						)
						(arc
							(start -0.1016 0.1778)
							(mid -0.137521 0.162921)
							(end -0.1524 0.127)
						)
						(arc
							(start -0.1524 -0.127)
							(mid -0.137521 -0.162921)
							(end -0.1016 -0.1778)
						)
						(arc
							(start 0.1016 -0.1778)
							(mid 0.137521 -0.162921)
							(end 0.1524 -0.127)
						)
					)
					(width 0)
					(fill yes)
				)
			)
		)
		(pad "2" smd custom
			(at 0 0.2794)
			(size 0.0762 0.0762)
			(layers "B.Cu" "B.Mask" "B.Paste")
			(net "PHY_DPB_TO_SCC_C_32_DP")
			(options
				(clearance outline)
				(anchor circle)
			)
			(primitives
				(gr_poly
					(pts
						(arc
							(start 0.1524 0.127)
							(mid 0.137521 0.162921)
							(end 0.1016 0.1778)
						)
						(arc
							(start -0.1016 0.1778)
							(mid -0.137521 0.162921)
							(end -0.1524 0.127)
						)
						(arc
							(start -0.1524 -0.127)
							(mid -0.137521 -0.162921)
							(end -0.1016 -0.1778)
						)
						(arc
							(start 0.1016 -0.1778)
							(mid 0.137521 -0.162921)
							(end 0.1524 -0.127)
						)
					)
					(width 0)
					(fill yes)
				)
			)
		)
	)
	(footprint ""
		(layer "B.Cu")
		(at 184.465468 -48.05299 90)
		(property "Reference" "C457"
			(at 0 0 90)
			(layer "B.SilkS")
			(hide yes)
			(effects
				(font
					(size 1.27 1.27)
				)
				(justify mirror)
			)
		)
		(property "Value" "SCD1U6D3V1KX-GP"
			(at 2.8321 -1.7399 90)
			(unlocked yes)
			(layer "B.Fab")
			(hide yes)
			(effects
				(font
					(size 1.016 1.016)
					(thickness 0.1524)
				)
				(justify mirror)
			)
		)
		(property "Device Type" "C0201H13"
			(at 2.8321 -3.2639 90)
			(unlocked yes)
			(layer "B.Fab")
			(hide yes)
			(effects
				(font
					(size 1.016 1.016)
					(thickness 0.1524)
				)
				(justify mirror)
			)
		)
		(duplicate_pad_numbers_are_jumpers no)
		(fp_rect
			(start 0.2794 0.6477)
			(end -0.2794 -0.6477)
			(stroke
				(width 0)
				(type default)
			)
			(fill no)
			(layer "B.CrtYd")
		)
		(fp_rect
			(start 0.2794 0.6477)
			(end -0.2794 -0.6477)
			(stroke
				(width 0)
				(type default)
			)
			(fill no)
			(layer "B.Fab")
		)
		(pad "1" smd custom
			(at 0 -0.2794 270)
			(size 0.0762 0.0762)
			(layers "B.Cu" "B.Mask" "B.Paste")
			(net "P1V8_C")
			(options
				(clearance outline)
				(anchor circle)
			)
			(primitives
				(gr_poly
					(pts
						(arc
							(start 0.1524 0.127)
							(mid 0.137521 0.162921)
							(end 0.1016 0.1778)
						)
						(arc
							(start -0.1016 0.1778)
							(mid -0.137521 0.162921)
							(end -0.1524 0.127)
						)
						(arc
							(start -0.1524 -0.127)
							(mid -0.137521 -0.162921)
							(end -0.1016 -0.1778)
						)
						(arc
							(start 0.1016 -0.1778)
							(mid 0.137521 -0.162921)
							(end 0.1524 -0.127)
						)
					)
					(width 0)
					(fill yes)
				)
			)
		)
		(pad "2" smd custom
			(at 0 0.2794 270)
			(size 0.0762 0.0762)
			(layers "B.Cu" "B.Mask" "B.Paste")
			(net "GND")
			(options
				(clearance outline)
				(anchor circle)
			)
			(primitives
				(gr_poly
					(pts
						(arc
							(start 0.1524 0.127)
							(mid 0.137521 0.162921)
							(end 0.1016 0.1778)
						)
						(arc
							(start -0.1016 0.1778)
							(mid -0.137521 0.162921)
							(end -0.1524 0.127)
						)
						(arc
							(start -0.1524 -0.127)
							(mid -0.137521 -0.162921)
							(end -0.1016 -0.1778)
						)
						(arc
							(start 0.1016 -0.1778)
							(mid 0.137521 -0.162921)
							(end 0.1524 -0.127)
						)
					)
					(width 0)
					(fill yes)
				)
			)
		)
	)
	(footprint ""
		(layer "B.Cu")
		(at 182.140098 -24.735536)
		(property "Reference" "TP129"
			(at 0 0 0)
			(layer "B.SilkS")
			(hide yes)
			(effects
				(font
					(size 1.27 1.27)
				)
				(justify mirror)
			)
		)
		(property "Value" "TPAD28-2-GP"
			(at 0.0127 -1.6637 0)
			(unlocked yes)
			(layer "B.Fab")
			(hide yes)
			(effects
				(font
					(size 1.016 1.016)
					(thickness 0.1524)
				)
				(justify mirror)
			)
		)
		(property "Device Type" "TPAD28"
			(at 0.0127 -3.1877 0)
			(unlocked yes)
			(layer "B.Fab")
			(hide yes)
			(effects
				(font
					(size 1.016 1.016)
					(thickness 0.1524)
				)
				(justify mirror)
			)
		)
		(duplicate_pad_numbers_are_jumpers no)
		(fp_poly
			(pts
				(arc
					(start 0.3556 0)
					(mid -0.3556 0)
					(end 0.3556 0)
				)
			)
			(stroke
				(width 0)
				(type default)
			)
			(fill no)
			(layer "B.CrtYd")
		)
		(fp_poly
			(pts
				(arc
					(start 0.6096 0)
					(mid -0.6096 0)
					(end 0.6096 0)
				)
			)
			(stroke
				(width 0)
				(type default)
			)
			(fill no)
			(layer "B.Fab")
		)
		(pad "1" smd circle
			(at 0 0 180)
			(size 0.7112 0.7112)
			(layers "B.Cu" "B.Mask" "B.Paste")
			(net "SYS_ERROR1")
		)
	)
	(footprint ""
		(layer "B.Cu")
		(at 154.184604 -62.090808 -90)
		(property "Reference" "C356"
			(at 0 0 90)
			(layer "B.SilkS")
			(hide yes)
			(effects
				(font
					(size 1.27 1.27)
				)
				(justify mirror)
			)
		)
		(property "Value" "SC10U6D3V5KX-4GP"
			(at 0.0762 -6.1214 270)
			(unlocked yes)
			(layer "B.Fab")
			(hide yes)
			(effects
				(font
					(size 1.016 1.016)
					(thickness 0.1524)
				)
				(justify mirror)
			)
		)
		(property "Device Type" "C805H58"
			(at 0.0762 -8.1534 270)
			(unlocked yes)
			(layer "B.Fab")
			(hide yes)
			(effects
				(font
					(size 1.016 1.016)
					(thickness 0.1524)
				)
				(justify mirror)
			)
		)
		(duplicate_pad_numbers_are_jumpers no)
		(fp_line
			(start -0.635 0)
			(end 0.635 0)
			(stroke
				(width 0.508)
				(type default)
			)
			(layer "B.SilkS")
		)
		(fp_rect
			(start 0.9652 1.778)
			(end -0.9652 -1.778)
			(stroke
				(width 0)
				(type default)
			)
			(fill no)
			(layer "B.CrtYd")
		)
		(fp_poly
			(pts
				(xy 0.9652 -1.778) (xy -0.9652 -1.778) (xy -0.9652 1.778) (xy 0.9652 1.778)
			)
			(stroke
				(width 0)
				(type default)
			)
			(fill no)
			(layer "B.Fab")
		)
		(pad "1" smd rect
			(at 0 -0.9652 90)
			(size 1.397 1.143)
			(layers "B.Cu" "B.Mask" "B.Paste")
			(net "SYS_PLL_VDD")
		)
		(pad "2" smd rect
			(at 0 0.9652 90)
			(size 1.397 1.143)
			(layers "B.Cu" "B.Mask" "B.Paste")
			(net "GND")
		)
	)
)
